# T6G (Grand Teton) — schematic netlist excerpt (pin names and nets, part order shuffled) for the footprints in the layout excerpt that follows; sources: Cadence DE-HDL packaged netlist, KiCad conversion of 04192023_DAF0TMB3IC0_F0TG_MB_C_brd_V02_OCP.brd

C858  Q_CAP_DIFFBUS  DIFF BUS_0.22UF 6.3V 20% X6S  pkg C0201  page 64 : \1\ = P5E_CPU0_P2_TX_C_DN<5> ; \2\ = P5E_CPU0_P2_TX_DN<5>
R917  Q_RES  10K 1% CHIP  pkg 0201LF  page 353 : A = GPIO3_RT_CPU1_P3 ; B = GND
R3435  Q_RES  4.7K 5% CHIP  pkg 0402LF  page 126 : A = P3V3_AUX ; B = GPU_FPGA_OVERT

(kicad_pcb
	(version 20260206)
	(generator "pcbnew")
	(generator_version "10.0")
	(general
		(thickness 1.6)
		(legacy_teardrops no)
	)
	(paper "A4")
	(title_block
		(title "04192023_DAF0TMB3IC0_F0TG_MB_C_brd_V02_OCP.brd")
		(comment 1 "Grand Teton / footprints 2490-2492 of 8354")
	)
	(layers
		(0 "F.Cu" signal "TOP")
		(4 "In1.Cu" signal "GND")
		(6 "In2.Cu" signal "IN1")
		(8 "In3.Cu" signal "GND1")
		(10 "In4.Cu" signal "IN2")
		(12 "In5.Cu" signal "GND2")
		(14 "In6.Cu" signal "IN3")
		(16 "In7.Cu" signal "GND3")
		(18 "In8.Cu" signal "VCC")
		(20 "In9.Cu" signal "VCC1")
		(22 "In10.Cu" signal "GND4")
		(24 "In11.Cu" signal "IN4")
		(26 "In12.Cu" signal "GND5")
		(28 "In13.Cu" signal "IN5")
		(30 "In14.Cu" signal "GND6")
		(32 "In15.Cu" signal "IN6")
		(34 "In16.Cu" signal "GND7")
		(2 "B.Cu" signal "BOTTOM")
		(9 "F.Adhes" user "F.Adhesive")
		(11 "B.Adhes" user "B.Adhesive")
		(13 "F.Paste" user "Package Geometry/Pastemask Top")
		(15 "B.Paste" user "Package Geometry/Pastemask Bottom")
		(5 "F.SilkS" user "Ref Des/Silkscreen Top")
		(7 "B.SilkS" user "Ref Des/Silkscreen Bottom")
		(1 "F.Mask" user "Board Geometry/Soldermask Top")
		(3 "B.Mask" user "Board Geometry/Soldermask Bottom")
		(17 "Dwgs.User" user "User.Drawings")
		(19 "Cmts.User" user "User.Comments")
		(21 "Eco1.User" user "User.Eco1")
		(23 "Eco2.User" user "User.Eco2")
		(25 "Edge.Cuts" user "Board Geometry/Outline")
		(27 "Margin" user)
		(31 "F.CrtYd" user "Package Geometry/Place Bound Top")
		(29 "B.CrtYd" user "Package Geometry/Place Bound Bottom")
		(35 "F.Fab" user "Ref Des/Assembly Top")
		(33 "B.Fab" user "Ref Des/Assembly Bottom")
	)
	(footprint ""
		(layer "F.Cu")
		(at 302.109378 -435.233572 -90)
		(property "Reference" "R3435"
			(at 0 0 270)
			(layer "F.SilkS")
			(hide yes)
			(effects
				(font
					(size 1.27 1.27)
				)
			)
		)
		(property "Value" ""
			(at 0 0 270)
			(layer "F.Fab")
			(effects
				(font
					(size 1.27 1.27)
				)
			)
		)
		(duplicate_pad_numbers_are_jumpers no)
		(fp_line
			(start -0.7874 0.4064)
			(end -0.7874 -0.4064)
			(stroke
				(width 0.1524)
				(type default)
			)
			(layer "F.SilkS")
		)
		(fp_line
			(start 0.7874 0.4064)
			(end -0.7874 0.4064)
			(stroke
				(width 0.1524)
				(type default)
			)
			(layer "F.SilkS")
		)
		(fp_line
			(start -0.7874 -0.4064)
			(end 0.7874 -0.4064)
			(stroke
				(width 0.1524)
				(type default)
			)
			(layer "F.SilkS")
		)
		(fp_line
			(start 0.7874 -0.4064)
			(end 0.7874 0.4064)
			(stroke
				(width 0.1524)
				(type default)
			)
			(layer "F.SilkS")
		)
		(fp_line
			(start -0.67945 0.3048)
			(end -0.67945 -0.305054)
			(stroke
				(width 0.1)
				(type default)
			)
			(layer "F.Fab")
		)
		(fp_line
			(start -0.12065 0.3048)
			(end -0.67945 0.3048)
			(stroke
				(width 0.1)
				(type default)
			)
			(layer "F.Fab")
		)
		(fp_line
			(start 0.120396 0.3048)
			(end 0.120396 0.2794)
			(stroke
				(width 0.1)
				(type default)
			)
			(layer "F.Fab")
		)
		(fp_line
			(start 0.67945 0.3048)
			(end 0.120396 0.3048)
			(stroke
				(width 0.1)
				(type default)
			)
			(layer "F.Fab")
		)
		(fp_line
			(start -0.12065 0.2794)
			(end -0.12065 0.3048)
			(stroke
				(width 0.1)
				(type default)
			)
			(layer "F.Fab")
		)
		(fp_line
			(start 0.120396 0.2794)
			(end -0.12065 0.2794)
			(stroke
				(width 0.1)
				(type default)
			)
			(layer "F.Fab")
		)
		(fp_line
			(start -0.12065 -0.2794)
			(end 0.12065 -0.2794)
			(stroke
				(width 0.1)
				(type default)
			)
			(layer "F.Fab")
		)
		(fp_line
			(start 0.12065 -0.2794)
			(end 0.12065 -0.3048)
			(stroke
				(width 0.1)
				(type default)
			)
			(layer "F.Fab")
		)
		(fp_line
			(start 0.12065 -0.3048)
			(end 0.67945 -0.3048)
			(stroke
				(width 0.1)
				(type default)
			)
			(layer "F.Fab")
		)
		(fp_line
			(start 0.67945 -0.3048)
			(end 0.67945 0.3048)
			(stroke
				(width 0.1)
				(type default)
			)
			(layer "F.Fab")
		)
		(fp_line
			(start -0.67945 -0.305054)
			(end -0.12065 -0.305054)
			(stroke
				(width 0.1)
				(type default)
			)
			(layer "F.Fab")
		)
		(fp_line
			(start -0.12065 -0.305054)
			(end -0.12065 -0.2794)
			(stroke
				(width 0.1)
				(type default)
			)
			(layer "F.Fab")
		)
		(pad "1" smd circle
			(at -0.40005 0 270)
			(size 0 0)
			(layers "F.Cu" "F.Mask" "F.Paste")
			(net "P3V3_AUX")
		)
		(pad "2" smd circle
			(at 0.40005 0 270)
			(size 0 0)
			(layers "F.Cu" "F.Mask" "F.Paste")
			(net "GPU_FPGA_OVERT")
		)
	)
	(footprint ""
		(layer "F.Cu")
		(at 406.33904 -381.41783 -90)
		(property "Reference" "C858"
			(at 0 0 270)
			(layer "F.SilkS")
			(hide yes)
			(effects
				(font
					(size 1.27 1.27)
				)
			)
		)
		(property "Value" ""
			(at 0 0 270)
			(layer "F.Fab")
			(effects
				(font
					(size 1.27 1.27)
				)
			)
		)
		(duplicate_pad_numbers_are_jumpers no)
		(fp_line
			(start -0.299974 0.150114)
			(end -0.299974 -0.150114)
			(stroke
				(width 0.1)
				(type default)
			)
			(layer "F.Fab")
		)
		(fp_line
			(start 0.299974 0.150114)
			(end -0.299974 0.150114)
			(stroke
				(width 0.1)
				(type default)
			)
			(layer "F.Fab")
		)
		(fp_line
			(start -0.299974 -0.150114)
			(end 0.299974 -0.150114)
			(stroke
				(width 0.1)
				(type default)
			)
			(layer "F.Fab")
		)
		(fp_line
			(start 0.299974 -0.150114)
			(end 0.299974 0.150114)
			(stroke
				(width 0.1)
				(type default)
			)
			(layer "F.Fab")
		)
		(pad "1" smd rect
			(at -0.2667 0 270)
			(size 0.3048 0.381)
			(layers "F.Cu" "F.Mask" "F.Paste")
			(net "P5E_CPU0_P2_TX_C_DN<5>")
		)
		(pad "2" smd rect
			(at 0.2667 0 270)
			(size 0.3048 0.381)
			(layers "F.Cu" "F.Mask" "F.Paste")
			(net "P5E_CPU0_P2_TX_DN<5>")
		)
	)
	(footprint ""
		(layer "F.Cu")
		(at 110.365794 -384.66268)
		(property "Reference" "R917"
			(at 0 0 0)
			(layer "F.SilkS")
			(hide yes)
			(effects
				(font
					(size 1.27 1.27)
				)
			)
		)
		(property "Value" ""
			(at 0 0 0)
			(layer "F.Fab")
			(effects
				(font
					(size 1.27 1.27)
				)
			)
		)
		(duplicate_pad_numbers_are_jumpers no)
		(fp_line
			(start -0.32512 -0.175006)
			(end 0.32512 -0.175006)
			(stroke
				(width 0.1)
				(type default)
			)
			(layer "F.Fab")
		)
		(fp_line
			(start -0.32512 0.175006)
			(end -0.32512 -0.175006)
			(stroke
				(width 0.1)
				(type default)
			)
			(layer "F.Fab")
		)
		(fp_line
			(start 0.32512 -0.175006)
			(end 0.32512 0.175006)
			(stroke
				(width 0.1)
				(type default)
			)
			(layer "F.Fab")
		)
		(fp_line
			(start 0.32512 0.175006)
			(end -0.32512 0.175006)
			(stroke
				(width 0.1)
				(type default)
			)
			(layer "F.Fab")
		)
		(pad "1" smd rect
			(at -0.2667 0)
			(size 0.3048 0.381)
			(layers "F.Cu" "F.Mask" "F.Paste")
			(net "GPIO3_RT_CPU1_P3")
		)
		(pad "2" smd rect
			(at 0.2667 0 180)
			(size 0.3048 0.381)
			(layers "F.Cu" "F.Mask" "F.Paste")
			(net "GND")
		)
	)
)
